(kicad_pcb
	(version 20260206)
	(generator "pcbnew")
	(generator_version "10.0")
	(general
		(thickness 1.6)
		(legacy_teardrops no)
	)
	(paper "A4")
	(title_block
		(title "pdpb — Lightning_PDPB_BRD.brd")
		(comment 1 "Lightning (Wiwynn / Facebook NVMe JBOF) / footprints 1088-1094 of 1140")
	)
	(layers
		(0 "F.Cu" signal "TOP")
		(4 "In1.Cu" signal "L2GND")
		(6 "In2.Cu" signal "L3")
		(8 "In3.Cu" signal "L4VCC")
		(10 "In4.Cu" signal "L5VCC")
		(12 "In5.Cu" signal "L6")
		(14 "In6.Cu" signal "L7GND")
		(2 "B.Cu" signal "BOTTOM")
		(9 "F.Adhes" user "F.Adhesive")
		(11 "B.Adhes" user "B.Adhesive")
		(13 "F.Paste" user "Package Geometry/Pastemask Top")
		(15 "B.Paste" user "Package Geometry/Pastemask Bottom")
		(5 "F.SilkS" user "Ref Des/Silkscreen Top")
		(7 "B.SilkS" user "Ref Des/Silkscreen Bottom")
		(1 "F.Mask" user "Board Geometry/Soldermask Top")
		(3 "B.Mask" user "Board Geometry/Soldermask Bottom")
		(17 "Dwgs.User" user "User.Drawings")
		(19 "Cmts.User" user "User.Comments")
		(21 "Eco1.User" user "User.Eco1")
		(23 "Eco2.User" user "User.Eco2")
		(25 "Edge.Cuts" user "Board Geometry/Outline")
		(27 "Margin" user)
		(31 "F.CrtYd" user "Package Geometry/Place Bound Top")
		(29 "B.CrtYd" user "Package Geometry/Place Bound Bottom")
		(35 "F.Fab" user "Ref Des/Assembly Top")
		(33 "B.Fab" user "Ref Des/Assembly Bottom")
	)
	(footprint ""
		(layer "F.Cu")
		(at 24.3078 -87.122 180)
		(property "Reference" "R575"
			(at 0 0 180)
			(layer "F.SilkS")
			(hide yes)
			(effects
				(font
					(size 1.27 1.27)
				)
			)
		)
		(property "Value" "300KR2F-GP"
			(at 0.064008 -3.993896 180)
			(unlocked yes)
			(layer "F.Fab")
			(hide yes)
			(effects
				(font
					(size 1.016 1.016)
					(thickness 0.1524)
				)
			)
		)
		(property "Device Type" "R402H16"
			(at 0.064008 -5.517896 180)
			(unlocked yes)
			(layer "F.Fab")
			(hide yes)
			(effects
				(font
					(size 1.016 1.016)
					(thickness 0.1524)
				)
			)
		)
		(duplicate_pad_numbers_are_jumpers no)
		(fp_line
			(start 0.508 -0.9398)
			(end -0.508 -0.9398)
			(stroke
				(width 0.1524)
				(type default)
			)
			(layer "F.SilkS")
		)
		(fp_line
			(start -0.508 -0.9398)
			(end -0.508 0.9398)
			(stroke
				(width 0.1524)
				(type default)
			)
			(layer "F.SilkS")
		)
		(fp_rect
			(start -0.508 0.9398)
			(end 0.508 -0.9398)
			(stroke
				(width 0)
				(type default)
			)
			(fill no)
			(layer "F.CrtYd")
		)
		(fp_rect
			(start -0.508 0.9398)
			(end 0.508 -0.9398)
			(stroke
				(width 0)
				(type default)
			)
			(fill no)
			(layer "F.Fab")
		)
		(pad "1" smd custom
			(at 0 -0.4445 180)
			(size 0.1397 0.1397)
			(layers "F.Cu" "F.Mask" "F.Paste")
			(net "SW_SSD9_N")
			(options
				(clearance outline)
				(anchor circle)
			)
			(primitives
				(gr_poly
					(pts
						(arc
							(start -0.1778 -0.2794)
							(mid -0.249642 -0.249642)
							(end -0.2794 -0.1778)
						)
						(arc
							(start -0.2794 0.1778)
							(mid -0.249642 0.249642)
							(end -0.1778 0.2794)
						)
						(arc
							(start 0.1778 0.2794)
							(mid 0.249642 0.249642)
							(end 0.2794 0.1778)
						)
						(arc
							(start 0.2794 -0.1778)
							(mid 0.249642 -0.249642)
							(end 0.1778 -0.2794)
						)
					)
					(width 0)
					(fill yes)
				)
			)
		)
		(pad "2" smd custom
			(at 0 0.4445 180)
			(size 0.1397 0.1397)
			(layers "F.Cu" "F.Mask" "F.Paste")
			(net "P12V")
			(options
				(clearance outline)
				(anchor circle)
			)
			(primitives
				(gr_poly
					(pts
						(arc
							(start -0.1778 -0.2794)
							(mid -0.249642 -0.249642)
							(end -0.2794 -0.1778)
						)
						(arc
							(start -0.2794 0.1778)
							(mid -0.249642 0.249642)
							(end -0.1778 0.2794)
						)
						(arc
							(start 0.1778 0.2794)
							(mid 0.249642 0.249642)
							(end 0.2794 0.1778)
						)
						(arc
							(start 0.2794 -0.1778)
							(mid 0.249642 -0.249642)
							(end 0.1778 -0.2794)
						)
					)
					(width 0)
					(fill yes)
				)
			)
		)
	)
	(footprint ""
		(layer "F.Cu")
		(at 20.066 -167.380158 -90)
		(property "Reference" "R9867"
			(at 0 0 270)
			(layer "F.SilkS")
			(hide yes)
			(effects
				(font
					(size 1.27 1.27)
				)
			)
		)
		(property "Value" "0R2J-2-GP"
			(at 0.064008 -3.993896 270)
			(unlocked yes)
			(layer "F.Fab")
			(hide yes)
			(effects
				(font
					(size 1.016 1.016)
					(thickness 0.1524)
				)
			)
		)
		(property "Device Type" "R402H16"
			(at 0.064008 -5.517896 270)
			(unlocked yes)
			(layer "F.Fab")
			(hide yes)
			(effects
				(font
					(size 1.016 1.016)
					(thickness 0.1524)
				)
			)
		)
		(duplicate_pad_numbers_are_jumpers no)
		(fp_line
			(start -0.508 -0.9398)
			(end -0.508 0.9398)
			(stroke
				(width 0.1524)
				(type default)
			)
			(layer "F.SilkS")
		)
		(fp_line
			(start 0.508 -0.9398)
			(end -0.508 -0.9398)
			(stroke
				(width 0.1524)
				(type default)
			)
			(layer "F.SilkS")
		)
		(fp_rect
			(start -0.508 0.9398)
			(end 0.508 -0.9398)
			(stroke
				(width 0)
				(type default)
			)
			(fill no)
			(layer "F.CrtYd")
		)
		(fp_rect
			(start -0.508 0.9398)
			(end 0.508 -0.9398)
			(stroke
				(width 0)
				(type default)
			)
			(fill no)
			(layer "F.Fab")
		)
		(pad "1" smd custom
			(at 0 -0.4445 270)
			(size 0.1397 0.1397)
			(layers "F.Cu" "F.Mask" "F.Paste")
			(net "ATTN_LED_DR13_AND")
			(options
				(clearance outline)
				(anchor circle)
			)
			(primitives
				(gr_poly
					(pts
						(arc
							(start -0.1778 -0.2794)
							(mid -0.249642 -0.249642)
							(end -0.2794 -0.1778)
						)
						(arc
							(start -0.2794 0.1778)
							(mid -0.249642 0.249642)
							(end -0.1778 0.2794)
						)
						(arc
							(start 0.1778 0.2794)
							(mid 0.249642 0.249642)
							(end 0.2794 0.1778)
						)
						(arc
							(start 0.2794 -0.1778)
							(mid 0.249642 -0.249642)
							(end 0.1778 -0.2794)
						)
					)
					(width 0)
					(fill yes)
				)
			)
		)
		(pad "2" smd custom
			(at 0 0.4445 270)
			(size 0.1397 0.1397)
			(layers "F.Cu" "F.Mask" "F.Paste")
			(net "ATTN_LED_DR13_AND_R")
			(options
				(clearance outline)
				(anchor circle)
			)
			(primitives
				(gr_poly
					(pts
						(arc
							(start -0.1778 -0.2794)
							(mid -0.249642 -0.249642)
							(end -0.2794 -0.1778)
						)
						(arc
							(start -0.2794 0.1778)
							(mid -0.249642 0.249642)
							(end -0.1778 0.2794)
						)
						(arc
							(start 0.1778 0.2794)
							(mid 0.249642 0.249642)
							(end 0.2794 0.1778)
						)
						(arc
							(start 0.2794 -0.1778)
							(mid 0.249642 -0.249642)
							(end 0.1778 -0.2794)
						)
					)
					(width 0)
					(fill yes)
				)
			)
		)
	)
	(footprint ""
		(layer "F.Cu")
		(at 89.789 -222.885 -90)
		(property "Reference" "C9361"
			(at 0 0 270)
			(layer "F.SilkS")
			(hide yes)
			(effects
				(font
					(size 1.27 1.27)
				)
			)
		)
		(property "Value" "SC1KP50V2KX-1GP"
			(at 1.1811 -2.7051 270)
			(unlocked yes)
			(layer "F.Fab")
			(hide yes)
			(effects
				(font
					(size 1.016 1.016)
					(thickness 0.1524)
				)
			)
		)
		(property "Device Type" "C402H22"
			(at 1.1811 -4.2291 270)
			(unlocked yes)
			(layer "F.Fab")
			(hide yes)
			(effects
				(font
					(size 1.016 1.016)
					(thickness 0.1524)
				)
			)
		)
		(duplicate_pad_numbers_are_jumpers no)
		(fp_rect
			(start -0.4318 0.9525)
			(end 0.4318 -0.9525)
			(stroke
				(width 0)
				(type default)
			)
			(fill no)
			(layer "F.CrtYd")
		)
		(fp_rect
			(start -0.4318 0.9525)
			(end 0.4318 -0.9525)
			(stroke
				(width 0)
				(type default)
			)
			(fill no)
			(layer "F.Fab")
		)
		(pad "1" smd custom
			(at 0 -0.4445 270)
			(size 0.1524 0.1524)
			(layers "F.Cu" "F.Mask" "F.Paste")
			(net "SSD_PRSNT12")
			(options
				(clearance outline)
				(anchor circle)
			)
			(primitives
				(gr_poly
					(pts
						(arc
							(start 0.3048 -0.2032)
							(mid 0.275042 -0.275042)
							(end 0.2032 -0.3048)
						)
						(arc
							(start -0.2032 -0.3048)
							(mid -0.275042 -0.275042)
							(end -0.3048 -0.2032)
						)
						(arc
							(start -0.3048 0.2032)
							(mid -0.275042 0.275042)
							(end -0.2032 0.3048)
						)
						(arc
							(start 0.2032 0.3048)
							(mid 0.275042 0.275042)
							(end 0.3048 0.2032)
						)
					)
					(width 0)
					(fill yes)
				)
			)
		)
		(pad "2" smd custom
			(at 0 0.4445 270)
			(size 0.1524 0.1524)
			(layers "F.Cu" "F.Mask" "F.Paste")
			(net "GND")
			(options
				(clearance outline)
				(anchor circle)
			)
			(primitives
				(gr_poly
					(pts
						(arc
							(start 0.3048 -0.2032)
							(mid 0.275042 -0.275042)
							(end 0.2032 -0.3048)
						)
						(arc
							(start -0.2032 -0.3048)
							(mid -0.275042 -0.275042)
							(end -0.3048 -0.2032)
						)
						(arc
							(start -0.3048 0.2032)
							(mid -0.275042 0.275042)
							(end -0.2032 0.3048)
						)
						(arc
							(start 0.2032 0.3048)
							(mid 0.275042 0.275042)
							(end 0.3048 0.2032)
						)
					)
					(width 0)
					(fill yes)
				)
			)
		)
	)
	(footprint ""
		(layer "F.Cu")
		(at 87.63 -88.138 180)
		(property "Reference" "R9606"
			(at 0 0 180)
			(layer "F.SilkS")
			(hide yes)
			(effects
				(font
					(size 1.27 1.27)
				)
			)
		)
		(property "Value" "10R2F-L-GP"
			(at 0.064008 -3.993896 180)
			(unlocked yes)
			(layer "F.Fab")
			(hide yes)
			(effects
				(font
					(size 1.016 1.016)
					(thickness 0.1524)
				)
			)
		)
		(property "Device Type" "R402H14"
			(at 0.064008 -5.517896 180)
			(unlocked yes)
			(layer "F.Fab")
			(hide yes)
			(effects
				(font
					(size 1.016 1.016)
					(thickness 0.1524)
				)
			)
		)
		(duplicate_pad_numbers_are_jumpers no)
		(fp_line
			(start 0.508 -0.9398)
			(end -0.508 -0.9398)
			(stroke
				(width 0.1524)
				(type default)
			)
			(layer "F.SilkS")
		)
		(fp_line
			(start -0.508 -0.9398)
			(end -0.508 0.9398)
			(stroke
				(width 0.1524)
				(type default)
			)
			(layer "F.SilkS")
		)
		(fp_rect
			(start -0.508 0.9398)
			(end 0.508 -0.9398)
			(stroke
				(width 0)
				(type default)
			)
			(fill no)
			(layer "F.CrtYd")
		)
		(fp_rect
			(start -0.508 0.9398)
			(end 0.508 -0.9398)
			(stroke
				(width 0)
				(type default)
			)
			(fill no)
			(layer "F.Fab")
		)
		(pad "1" smd custom
			(at 0 -0.4445 180)
			(size 0.1397 0.1397)
			(layers "F.Cu" "F.Mask" "F.Paste")
			(net "SSD_PRSNT_NET9")
			(options
				(clearance outline)
				(anchor circle)
			)
			(primitives
				(gr_poly
					(pts
						(arc
							(start -0.1778 -0.2794)
							(mid -0.249642 -0.249642)
							(end -0.2794 -0.1778)
						)
						(arc
							(start -0.2794 0.1778)
							(mid -0.249642 0.249642)
							(end -0.1778 0.2794)
						)
						(arc
							(start 0.1778 0.2794)
							(mid 0.249642 0.249642)
							(end 0.2794 0.1778)
						)
						(arc
							(start 0.2794 -0.1778)
							(mid 0.249642 -0.249642)
							(end 0.1778 -0.2794)
						)
					)
					(width 0)
					(fill yes)
				)
			)
		)
		(pad "2" smd custom
			(at 0 0.4445 180)
			(size 0.1397 0.1397)
			(layers "F.Cu" "F.Mask" "F.Paste")
			(net "SSD_PRSNT9")
			(options
				(clearance outline)
				(anchor circle)
			)
			(primitives
				(gr_poly
					(pts
						(arc
							(start -0.1778 -0.2794)
							(mid -0.249642 -0.249642)
							(end -0.2794 -0.1778)
						)
						(arc
							(start -0.2794 0.1778)
							(mid -0.249642 0.249642)
							(end -0.1778 0.2794)
						)
						(arc
							(start 0.1778 0.2794)
							(mid 0.249642 0.249642)
							(end 0.2794 0.1778)
						)
						(arc
							(start 0.2794 -0.1778)
							(mid 0.249642 -0.249642)
							(end 0.1778 -0.2794)
						)
					)
					(width 0)
					(fill yes)
				)
			)
		)
	)
	(footprint ""
		(layer "F.Cu")
		(at 50.546 -136.398 180)
		(property "Reference" "R342"
			(at 0 0 180)
			(layer "F.SilkS")
			(hide yes)
			(effects
				(font
					(size 1.27 1.27)
				)
			)
		)
		(property "Value" "4K7R2F-GP"
			(at 0.064008 -3.993896 180)
			(unlocked yes)
			(layer "F.Fab")
			(hide yes)
			(effects
				(font
					(size 1.016 1.016)
					(thickness 0.1524)
				)
			)
		)
		(property "Device Type" "R402H16"
			(at 0.064008 -5.517896 180)
			(unlocked yes)
			(layer "F.Fab")
			(hide yes)
			(effects
				(font
					(size 1.016 1.016)
					(thickness 0.1524)
				)
			)
		)
		(duplicate_pad_numbers_are_jumpers no)
		(fp_line
			(start 0.508 -0.9398)
			(end -0.508 -0.9398)
			(stroke
				(width 0.1524)
				(type default)
			)
			(layer "F.SilkS")
		)
		(fp_line
			(start -0.508 -0.9398)
			(end -0.508 0.9398)
			(stroke
				(width 0.1524)
				(type default)
			)
			(layer "F.SilkS")
		)
		(fp_rect
			(start -0.508 0.9398)
			(end 0.508 -0.9398)
			(stroke
				(width 0)
				(type default)
			)
			(fill no)
			(layer "F.CrtYd")
		)
		(fp_rect
			(start -0.508 0.9398)
			(end 0.508 -0.9398)
			(stroke
				(width 0)
				(type default)
			)
			(fill no)
			(layer "F.Fab")
		)
		(pad "1" smd custom
			(at 0 -0.4445 180)
			(size 0.1397 0.1397)
			(layers "F.Cu" "F.Mask" "F.Paste")
			(net "I2C_B_TMP1_A1")
			(options
				(clearance outline)
				(anchor circle)
			)
			(primitives
				(gr_poly
					(pts
						(arc
							(start -0.1778 -0.2794)
							(mid -0.249642 -0.249642)
							(end -0.2794 -0.1778)
						)
						(arc
							(start -0.2794 0.1778)
							(mid -0.249642 0.249642)
							(end -0.1778 0.2794)
						)
						(arc
							(start 0.1778 0.2794)
							(mid 0.249642 0.249642)
							(end 0.2794 0.1778)
						)
						(arc
							(start 0.2794 -0.1778)
							(mid 0.249642 -0.249642)
							(end 0.1778 -0.2794)
						)
					)
					(width 0)
					(fill yes)
				)
			)
		)
		(pad "2" smd custom
			(at 0 0.4445 180)
			(size 0.1397 0.1397)
			(layers "F.Cu" "F.Mask" "F.Paste")
			(net "GND")
			(options
				(clearance outline)
				(anchor circle)
			)
			(primitives
				(gr_poly
					(pts
						(arc
							(start -0.1778 -0.2794)
							(mid -0.249642 -0.249642)
							(end -0.2794 -0.1778)
						)
						(arc
							(start -0.2794 0.1778)
							(mid -0.249642 0.249642)
							(end -0.1778 0.2794)
						)
						(arc
							(start 0.1778 0.2794)
							(mid 0.249642 0.249642)
							(end 0.2794 0.1778)
						)
						(arc
							(start 0.2794 -0.1778)
							(mid 0.249642 -0.249642)
							(end 0.1778 -0.2794)
						)
					)
					(width 0)
					(fill yes)
				)
			)
		)
	)
	(footprint ""
		(layer "F.Cu")
		(at 89.789 -446.786 90)
		(property "Reference" "R9416"
			(at 0 0 90)
			(layer "F.SilkS")
			(hide yes)
			(effects
				(font
					(size 1.27 1.27)
				)
			)
		)
		(property "Value" "4K7R2J-2-GP"
			(at 0.064008 -3.993896 90)
			(unlocked yes)
			(layer "F.Fab")
			(hide yes)
			(effects
				(font
					(size 1.016 1.016)
					(thickness 0.1524)
				)
			)
		)
		(property "Device Type" "R402H16"
			(at 0.064008 -5.517896 90)
			(unlocked yes)
			(layer "F.Fab")
			(hide yes)
			(effects
				(font
					(size 1.016 1.016)
					(thickness 0.1524)
				)
			)
		)
		(duplicate_pad_numbers_are_jumpers no)
		(fp_line
			(start 0.508 -0.9398)
			(end -0.508 -0.9398)
			(stroke
				(width 0.1524)
				(type default)
			)
			(layer "F.SilkS")
		)
		(fp_line
			(start -0.508 -0.9398)
			(end -0.508 0.9398)
			(stroke
				(width 0.1524)
				(type default)
			)
			(layer "F.SilkS")
		)
		(fp_rect
			(start -0.508 0.9398)
			(end 0.508 -0.9398)
			(stroke
				(width 0)
				(type default)
			)
			(fill no)
			(layer "F.CrtYd")
		)
		(fp_rect
			(start -0.508 0.9398)
			(end 0.508 -0.9398)
			(stroke
				(width 0)
				(type default)
			)
			(fill no)
			(layer "F.Fab")
		)
		(pad "1" smd custom
			(at 0 -0.4445 90)
			(size 0.1397 0.1397)
			(layers "F.Cu" "F.Mask" "F.Paste")
			(net "P3V3")
			(options
				(clearance outline)
				(anchor circle)
			)
			(primitives
				(gr_poly
					(pts
						(arc
							(start -0.1778 -0.2794)
							(mid -0.249642 -0.249642)
							(end -0.2794 -0.1778)
						)
						(arc
							(start -0.2794 0.1778)
							(mid -0.249642 0.249642)
							(end -0.1778 0.2794)
						)
						(arc
							(start 0.1778 0.2794)
							(mid 0.249642 0.249642)
							(end 0.2794 0.1778)
						)
						(arc
							(start 0.2794 -0.1778)
							(mid 0.249642 -0.249642)
							(end 0.1778 -0.2794)
						)
					)
					(width 0)
					(fill yes)
				)
			)
		)
		(pad "2" smd custom
			(at 0 0.4445 90)
			(size 0.1397 0.1397)
			(layers "F.Cu" "F.Mask" "F.Paste")
			(net "SSD_PRSNT_NET5")
			(options
				(clearance outline)
				(anchor circle)
			)
			(primitives
				(gr_poly
					(pts
						(arc
							(start -0.1778 -0.2794)
							(mid -0.249642 -0.249642)
							(end -0.2794 -0.1778)
						)
						(arc
							(start -0.2794 0.1778)
							(mid -0.249642 0.249642)
							(end -0.1778 0.2794)
						)
						(arc
							(start 0.1778 0.2794)
							(mid 0.249642 0.249642)
							(end 0.2794 0.1778)
						)
						(arc
							(start 0.2794 -0.1778)
							(mid 0.249642 -0.249642)
							(end 0.1778 -0.2794)
						)
					)
					(width 0)
					(fill yes)
				)
			)
		)
	)
	(footprint ""
		(layer "F.Cu")
		(at 99.314 -92.964)
		(property "Reference" "R9129"
			(at 0 0 0)
			(layer "F.SilkS")
			(hide yes)
			(effects
				(font
					(size 1.27 1.27)
				)
			)
		)
		(property "Value" "27R2F-GP"
			(at 0.064008 -3.993896 0)
			(unlocked yes)
			(layer "F.Fab")
			(hide yes)
			(effects
				(font
					(size 1.016 1.016)
					(thickness 0.1524)
				)
			)
		)
		(property "Device Type" "R402H16"
			(at 0.064008 -5.517896 0)
			(unlocked yes)
			(layer "F.Fab")
			(hide yes)
			(effects
				(font
					(size 1.016 1.016)
					(thickness 0.1524)
				)
			)
		)
		(duplicate_pad_numbers_are_jumpers no)
		(fp_line
			(start -0.508 -0.9398)
			(end -0.508 0.9398)
			(stroke
				(width 0.1524)
				(type default)
			)
			(layer "F.SilkS")
		)
		(fp_line
			(start 0.508 -0.9398)
			(end -0.508 -0.9398)
			(stroke
				(width 0.1524)
				(type default)
			)
			(layer "F.SilkS")
		)
		(fp_rect
			(start -0.508 0.9398)
			(end 0.508 -0.9398)
			(stroke
				(width 0)
				(type default)
			)
			(fill no)
			(layer "F.CrtYd")
		)
		(fp_rect
			(start -0.508 0.9398)
			(end 0.508 -0.9398)
			(stroke
				(width 0)
				(type default)
			)
			(fill no)
			(layer "F.Fab")
		)
		(pad "1" smd custom
			(at 0 -0.4445)
			(size 0.1397 0.1397)
			(layers "F.Cu" "F.Mask" "F.Paste")
			(net "PE_CLK_100M_DR14_1_R_P")
			(options
				(clearance outline)
				(anchor circle)
			)
			(primitives
				(gr_poly
					(pts
						(arc
							(start -0.1778 -0.2794)
							(mid -0.249642 -0.249642)
							(end -0.2794 -0.1778)
						)
						(arc
							(start -0.2794 0.1778)
							(mid -0.249642 0.249642)
							(end -0.1778 0.2794)
						)
						(arc
							(start 0.1778 0.2794)
							(mid 0.249642 0.249642)
							(end 0.2794 0.1778)
						)
						(arc
							(start 0.2794 -0.1778)
							(mid 0.249642 -0.249642)
							(end 0.1778 -0.2794)
						)
					)
					(width 0)
					(fill yes)
				)
			)
		)
		(pad "2" smd custom
			(at 0 0.4445)
			(size 0.1397 0.1397)
			(layers "F.Cu" "F.Mask" "F.Paste")
			(net "PE_CLK100M_DR14_1_P")
			(options
				(clearance outline)
				(anchor circle)
			)
			(primitives
				(gr_poly
					(pts
						(arc
							(start -0.1778 -0.2794)
							(mid -0.249642 -0.249642)
							(end -0.2794 -0.1778)
						)
						(arc
							(start -0.2794 0.1778)
							(mid -0.249642 0.249642)
							(end -0.1778 0.2794)
						)
						(arc
							(start 0.1778 0.2794)
							(mid 0.249642 0.249642)
							(end 0.2794 0.1778)
						)
						(arc
							(start 0.2794 -0.1778)
							(mid 0.249642 -0.249642)
							(end 0.1778 -0.2794)
						)
					)
					(width 0)
					(fill yes)
				)
			)
		)
	)
)
